(kicad_pcb
	(version 20221018)
	(generator pcbnew)
	(general
    (thickness 1.656)
  )
	(paper "A4")
	(title_block
    (title "SDI-MIPI Bridge")
    (date "2023-08-09")
    (rev "1.3.4")
    (company "Antmicro")
		(comment 9 "footprint 20 of 190 (U4), pads 78-80 of 80")
	)
	(layers
    (0 "F.Cu" signal)
    (1 "In1.Cu" power)
    (2 "In2.Cu" power)
    (3 "In3.Cu" signal)
    (4 "In4.Cu" signal)
    (31 "B.Cu" signal)
    (32 "B.Adhes" user "B.Adhesive")
    (33 "F.Adhes" user "F.Adhesive")
    (34 "B.Paste" user)
    (35 "F.Paste" user)
    (36 "B.SilkS" user "B.Silkscreen")
    (37 "F.SilkS" user "F.Silkscreen")
    (38 "B.Mask" user)
    (39 "F.Mask" user)
    (40 "Dwgs.User" user "User.Drawings")
    (41 "Cmts.User" user "User.Comments")
    (42 "Eco1.User" user "User.Eco1")
    (43 "Eco2.User" user "User.Eco2")
    (44 "Edge.Cuts" user)
    (45 "Margin" user)
    (46 "B.CrtYd" user "B.Courtyard")
    (47 "F.CrtYd" user "F.Courtyard")
    (48 "B.Fab" user)
    (49 "F.Fab" user)
  )
	(footprint "sdi-mipi-bridge-footprints:BGA-80_7x7mm_Layout10x10_P0.65mm"
    (layer "F.Cu")
    (at 145.57 115.89 -90)
    (property "Author" "Antmicro")
    (property "License" "Apache-2.0")
    (property "MPN" "LIF-MD6000-6JMG80I")
    (property "Manufacturer" "Lattice Semiconductor")
    (property "Sheetfile" "sdi-mipi-bridge.kicad_sch")
    (property "Sheetname" "")
    (property "ki_description" "FPGA, CrossLink, PLL37 I/O, 400 MHz, 5936 Cells, 1.14 V to 1.26 V, CTFBGA-80")
    (property "ki_keywords" "SMT, FPGA, IC")
    (attr smd)
    (fp_text reference "U4" (at -1.901 -4.55 90) (layer "F.SilkS")
        (effects (font (size 0.7 0.7) (thickness 0.15)) (justify right bottom))
    )
    (fp_text value "CrossLink_LIF-MD6000-6JMG80I" (at 0 4.65 90) (layer "F.Fab") hide
        (effects (font (size 0.7 0.7) (thickness 0.15)) (justify right bottom))
    )
    (pad "K8" smd circle (at 1.625 2.925 270) (size 0.35 0.35) (layers "F.Cu" "F.Paste" "F.Mask")
      (net 16 "/20bit_~{10bit}") (pinfunction "PB16C/PCLKT2_1") (pintype "bidirectional") (solder_mask_margin -0.025) (solder_paste_margin -0.025))
    (pad "K9" smd circle (at 2.275 2.925 270) (size 0.35 0.35) (layers "F.Cu" "F.Paste" "F.Mask")
      (net 17 "/~{SMPTE_BYPASS}") (pinfunction "PB12D") (pintype "bidirectional") (solder_mask_margin -0.025) (solder_paste_margin -0.025))
    (pad "K10" smd circle (at 2.925 2.925 270) (size 0.35 0.35) (layers "F.Cu" "F.Paste" "F.Mask")
      (net 18 "/DVB_ASI") (pinfunction "PB12C") (pintype "bidirectional") (solder_mask_margin -0.025) (solder_paste_margin -0.025))
  )
)
